G04 ================== begin FILE IDENTIFICATION RECORD ==================*
G04 Layout Name:  13948-1b.brd*
G04 Film Name:    WSILK_T*
G04 File Format:  Gerber RS274X*
G04 File Origin:  Cadence Allegro 16.5-S045*
G04 Origin Date:  Thu Nov 13 15:46:05 2014*
G04 *
G04 Layer:  DRAWING FORMAT/LAYER_WSILK_T*
G04 Layer:  DRAWING FORMAT/LAYER_PCB_STORY*
G04 Layer:  BOARD GEOMETRY/WSILK_T*
G04 Layer:  BOARD GEOMETRY/PANEL_OUTLINE*
G04 *
G04 Offset:    (0.00 0.00)*
G04 Mirror:    No*
G04 Mode:      Positive*
G04 Rotation:  0*
G04 FullContactRelief:  No*
G04 UndefLineWidth:     6.00*
G04 ================== end FILE IDENTIFICATION RECORD ====================*
%FSLAX35Y35*MOIN*%
%IR0*IPPOS*OFA0.00000B0.00000*MIA0B0*SFA1.00000B1.00000*%
%ADD10C,.02*%
%ADD11C,.006*%
%ADD12C,.008*%
G75*
%LPD*%
G75*
G54D10*
G01X-245081Y-422119D02*
G02I-12000J0D01*
G01X-250231D02*
G02I-6850J0D01*
G01X-241081D02*
X-273081D01*
G01X-257081Y-438119D02*
Y-406119D01*
G01X-241081Y-438119D02*
Y-518119D01*
G01D02*
X1034819D01*
G01X-241081Y-473619D02*
X1034819D01*
G01X-241081Y-438119D02*
X1034819D01*
G01X247319D02*
Y-518119D01*
G01X384819Y-438119D02*
Y-518119D01*
G01X499819Y-438119D02*
Y-518119D01*
G01X667319Y-438119D02*
Y-518119D01*
G01X837319Y-438119D02*
Y-518119D01*
G01X1034819Y-438119D02*
Y-518119D01*
G01X1066819Y-422119D02*
X1034819D01*
G01X1050819Y-438119D02*
Y-406119D01*
G01X1062819Y-422119D02*
G02I-12000J0D01*
G01X1057669D02*
G02I-6850J0D01*
G54D11*
G01X-185516Y-508119D02*
Y-490619D01*
G01X-176346D02*
Y-508119D01*
G01Y-499369D02*
X-185516D01*
G01X-163431Y-508119D02*
X-165178Y-507827D01*
X-166706Y-506661D01*
X-168016Y-504911D01*
X-168890Y-502869D01*
X-169326Y-500536D01*
Y-498202D01*
X-168890Y-495869D01*
X-168016Y-493827D01*
X-166706Y-492078D01*
X-165178Y-490911D01*
X-163431Y-490619D01*
X-161685Y-490911D01*
X-160156Y-492078D01*
X-158846Y-493827D01*
X-157972Y-495869D01*
X-157536Y-498202D01*
Y-500536D01*
X-157972Y-502869D01*
X-158846Y-504911D01*
X-160156Y-506661D01*
X-161685Y-507827D01*
X-163431Y-508119D01*
G01X-150953D02*
Y-490619D01*
X-140909Y-508119D01*
Y-490619D01*
G01X-124064Y-508119D02*
X-132798D01*
Y-490619D01*
X-124064D01*
G01X-127558Y-499077D02*
X-132798D01*
G01X-110931Y-508119D02*
Y-500244D01*
X-115298Y-490619D01*
G01X-106564D02*
X-110931Y-500244D01*
G01X-74185Y-498786D02*
X-73311Y-497911D01*
X-72656Y-496453D01*
X-72219Y-494410D01*
X-72656Y-492661D01*
X-73529Y-491494D01*
X-75058Y-490619D01*
X-80953D01*
Y-508119D01*
X-73748D01*
X-72219Y-506953D01*
X-71346Y-505202D01*
X-70909Y-503161D01*
X-71346Y-501119D01*
X-72656Y-499369D01*
X-74185Y-498786D01*
X-80953D01*
G01X-63890Y-508119D02*
X-58431Y-490619D01*
X-52972Y-508119D01*
G01X-54938Y-501994D02*
X-61925D01*
G01X-45734Y-508119D02*
Y-490619D01*
X-41368D01*
X-39621Y-491494D01*
X-38311Y-492661D01*
X-37219Y-494410D01*
X-36346Y-496453D01*
X-36128Y-499369D01*
X-36346Y-502286D01*
X-37219Y-504328D01*
X-38311Y-506078D01*
X-39621Y-507244D01*
X-41368Y-508119D01*
X-45734D01*
G01X-22121Y-499369D02*
X-17754D01*
Y-504619D01*
X-19064Y-506369D01*
X-20593Y-507536D01*
X-22776Y-508119D01*
X-24959Y-507536D01*
X-26488Y-506369D01*
X-27798Y-504619D01*
X-28671Y-502577D01*
X-29108Y-500244D01*
Y-498202D01*
X-28671Y-496453D01*
X-27798Y-494410D01*
X-26488Y-492661D01*
X-25178Y-491494D01*
X-23431Y-490619D01*
X-21903D01*
X-20156Y-491202D01*
X-18846Y-492369D01*
G01X-1564Y-508119D02*
X-10298D01*
Y-490619D01*
X-1564D01*
G01X-5058Y-499077D02*
X-10298D01*
G01X7202Y-508119D02*
Y-490619D01*
X12661D01*
X14407Y-491494D01*
X15499Y-492661D01*
X15936Y-494994D01*
X15499Y-497328D01*
X14189Y-498786D01*
X12661Y-499661D01*
X7202D01*
G01X12661D02*
X15936Y-508119D01*
G01X48315Y-498786D02*
X49189Y-497911D01*
X49844Y-496453D01*
X50281Y-494410D01*
X49844Y-492661D01*
X48971Y-491494D01*
X47442Y-490619D01*
X41547D01*
Y-508119D01*
X48752D01*
X50281Y-506953D01*
X51154Y-505202D01*
X51591Y-503161D01*
X51154Y-501119D01*
X49844Y-499369D01*
X48315Y-498786D01*
X41547D01*
G01X58610Y-508119D02*
X64069Y-490619D01*
X69528Y-508119D01*
G01X67562Y-501994D02*
X60575D01*
G01X76984Y-505786D02*
X78731Y-507244D01*
X80696Y-508119D01*
X82442D01*
X84189Y-507244D01*
X85499Y-505786D01*
X86154Y-503744D01*
X85717Y-501703D01*
X84626Y-499952D01*
X82661Y-498786D01*
X80041Y-498202D01*
X78512Y-497036D01*
X77857Y-494994D01*
X78294Y-492952D01*
X79386Y-491494D01*
X80914Y-490619D01*
X82442D01*
X83971Y-491202D01*
X85281Y-492661D01*
G01X103436Y-508119D02*
X94702D01*
Y-490619D01*
X103436D01*
G01X99942Y-499077D02*
X94702D01*
G01X118315Y-498786D02*
X119189Y-497911D01*
X119844Y-496453D01*
X120281Y-494410D01*
X119844Y-492661D01*
X118971Y-491494D01*
X117442Y-490619D01*
X111547D01*
Y-508119D01*
X118752D01*
X120281Y-506953D01*
X121154Y-505202D01*
X121591Y-503161D01*
X121154Y-501119D01*
X119844Y-499369D01*
X118315Y-498786D01*
X111547D01*
G01X134069Y-508119D02*
X132322Y-507827D01*
X130794Y-506661D01*
X129484Y-504911D01*
X128610Y-502869D01*
X128174Y-500536D01*
Y-498202D01*
X128610Y-495869D01*
X129484Y-493827D01*
X130794Y-492078D01*
X132322Y-490911D01*
X134069Y-490619D01*
X135815Y-490911D01*
X137344Y-492078D01*
X138654Y-493827D01*
X139528Y-495869D01*
X139964Y-498202D01*
Y-500536D01*
X139528Y-502869D01*
X138654Y-504911D01*
X137344Y-506661D01*
X135815Y-507827D01*
X134069Y-508119D01*
G01X146110D02*
X151569Y-490619D01*
X157028Y-508119D01*
G01X155062Y-501994D02*
X148075D01*
G01X164702Y-508119D02*
Y-490619D01*
X170161D01*
X171907Y-491494D01*
X172999Y-492661D01*
X173436Y-494994D01*
X172999Y-497328D01*
X171689Y-498786D01*
X170161Y-499661D01*
X164702D01*
G01X170161D02*
X173436Y-508119D01*
G01X181766D02*
Y-490619D01*
X186132D01*
X187879Y-491494D01*
X189189Y-492661D01*
X190281Y-494410D01*
X191154Y-496453D01*
X191372Y-499369D01*
X191154Y-502286D01*
X190281Y-504328D01*
X189189Y-506078D01*
X187879Y-507244D01*
X186132Y-508119D01*
X181766D01*
G01X-37858Y-463119D02*
Y-445619D01*
X-32181Y-460202D01*
X-26504Y-445619D01*
Y-463119D01*
G01X-14681D02*
X-15991Y-462827D01*
X-17301Y-461661D01*
X-18175Y-459619D01*
X-18611Y-457286D01*
X-18175Y-454952D01*
X-17301Y-452911D01*
X-15991Y-451744D01*
X-14681Y-451453D01*
X-13371Y-451744D01*
X-12061Y-452911D01*
X-11188Y-454952D01*
X-10969Y-457286D01*
X-11188Y-459619D01*
X-12061Y-461661D01*
X-13371Y-462827D01*
X-14681Y-463119D01*
G01X6749Y-445619D02*
Y-463119D01*
G01Y-460495D02*
X5876Y-461953D01*
X4565Y-462827D01*
X3037Y-463119D01*
X1291Y-462536D01*
X-19Y-461078D01*
X-893Y-459328D01*
X-1111Y-457286D01*
X-893Y-455244D01*
X-19Y-453494D01*
X1291Y-452036D01*
X3037Y-451453D01*
X4565Y-451744D01*
X5657Y-452328D01*
X6749Y-453494D01*
G01X17044Y-455244D02*
X24031D01*
X23376Y-453202D01*
X22284Y-452036D01*
X20756Y-451453D01*
X19227Y-451744D01*
X17917Y-452619D01*
X17044Y-454661D01*
X16607Y-456411D01*
Y-458161D01*
X17044Y-459911D01*
X18136Y-461661D01*
X19446Y-462827D01*
X20974Y-463119D01*
X22502Y-462536D01*
X24031Y-460786D01*
G01X37819Y-463119D02*
Y-445619D01*
G01X1Y-17717D02*
G03X7875Y-25591I7874J0D01*
G01X1Y299252D02*
Y-10394D01*
G01Y-17717D02*
G03X7875Y-25591I7874J0D01*
G01X1Y299252D02*
Y-10394D01*
G01Y-17717D02*
Y-10394D01*
G01D02*
Y-17723D01*
G01X0Y11811D02*
Y0D01*
G01X92520Y299252D02*
X1D01*
G01X92520D02*
X1D01*
G01X0Y318937D02*
G03X11811Y307126I11811J0D01*
G01X0Y968503D02*
Y318937D01*
G01X19685Y988189D02*
G03X0Y968503I0J-19685D01*
G01X43950Y996063D02*
X1D01*
G01X43950D02*
X1D01*
G01Y1008622D02*
Y996063D01*
G01Y1008622D02*
Y996063D01*
G01X15001Y1023622D02*
G03X1Y1008622I0J-15000D01*
G01X15001Y1023622D02*
G03X1Y1008622I0J-15000D01*
G01X7875Y-25591D02*
X45337D01*
G01X7875D02*
X45337D01*
G01X11811Y307126D02*
X100394D01*
G01X10710Y1008622D02*
G03X19292I4291J0D01*
G01D02*
G03X10710I-4291J0D01*
G01X99804Y1023622D02*
X15001D01*
G01X99804D02*
X15001D01*
G01X103740Y988189D02*
X19685D01*
G01X53211Y-25591D02*
G03X45337I-3937J0D01*
G01X53211D02*
G03X45337I-3937J0D01*
G01X53211D02*
G03X45337I-3937J0D01*
G01X53211D02*
G03X45337I-3937J0D01*
G01X43950Y988189D02*
G03Y996063I0J3937D01*
G01Y988189D02*
G03Y996063I0J3937D01*
G01X53211Y-25591D02*
X1392127D01*
G01X53211D02*
X1392127D01*
G01X69147Y996063D02*
G03Y988189I0J-3937D01*
G01Y996063D02*
G03Y988189I0J-3937D01*
G01X99804Y996063D02*
X69147D01*
G01X99804D02*
X69147D01*
G01X94412Y72220D02*
G03X85830Y72219I-4291J-1D01*
G01D02*
G03X94412Y72220I4291J0D01*
G01X100394Y291377D02*
G03X92520Y299252I-7874J1D01*
G01X100394Y291377D02*
G03X92520Y299252I-7874J1D01*
G01X99804Y1023622D02*
Y996063D01*
G01Y1023622D02*
Y996063D01*
G01X100394Y236259D02*
G03X116142Y220511I15748J0D01*
G01D02*
X232088D01*
G01X100394Y236259D02*
G03X116142Y220511I15748J0D01*
G01D02*
X232088D01*
G01X116142Y228385D02*
X239961D01*
G01X108268Y236259D02*
G03X116142Y228385I7874J0D01*
G01X108268Y299252D02*
Y236259D01*
G01X100395Y240899D02*
X100394Y236259D01*
G01X100395Y240899D02*
X100394Y236259D01*
G01X108269Y240899D02*
G03X100395I-3937J0D01*
G01X108269D02*
G03X100395I-3937J0D01*
G01Y266096D02*
G03X108269I3937J-1D01*
G01X100395D02*
G03X108269I3937J-1D01*
G01X100395D02*
X100394Y291377D01*
G01X100395Y266096D02*
X100394Y291377D01*
G01X108268Y299252D02*
G03X100394Y307126I-7874J0D01*
G01X103740Y988189D02*
G03X107677Y992126I0J3937D01*
G01Y1018109D02*
Y992126D01*
G01X136024Y1018109D02*
X136023Y1021653D01*
X134055Y1023622D01*
X109645D01*
X107677Y1021653D01*
Y1018109D01*
G01X136024Y994290D02*
G03X143505I3740J0D01*
G01X136024D02*
Y1018109D01*
G01X143504D02*
Y994290D01*
G01X187598Y1018109D02*
Y1021653D01*
X185630Y1023622D01*
X145472D01*
X143504Y1021653D01*
Y1018109D01*
G01X151575Y220511D02*
X226378D01*
G01X151575D02*
X226378D01*
G01X187598Y992126D02*
Y1018109D01*
G01Y992126D02*
G03X191535Y988189I3937J0D01*
G01X261220D02*
X191535D01*
G01X212681Y996063D02*
X195473D01*
G01D02*
Y1023622D01*
G01X212681Y996063D02*
X195473D01*
G01D02*
Y1023622D01*
G01D02*
X257284D01*
G01X195473D02*
X257284D01*
G01X212681Y988189D02*
G03Y996063I0J3937D01*
G01Y988189D02*
G03Y996063I0J3937D01*
G01X222751Y1008622D02*
G03X231333I4291J0D01*
G01D02*
G03X222751I-4291J0D01*
G01X243898Y70866D02*
G03X247835Y66928I3937J-1D01*
G01X243898Y224448D02*
Y70866D01*
G01X236025Y164487D02*
Y70866D01*
G01D02*
G03X247836Y59055I11811J0D01*
G01X236025Y164487D02*
Y70866D01*
G01D02*
G03X247836Y59055I11811J0D01*
G01X243899Y164487D02*
G03X236025I-3937J0D01*
G01X243899D02*
G03X236025I-3937J0D01*
G01Y189684D02*
G03X243899I3937J0D01*
G01X236025D02*
G03X243899I3937J0D01*
G01X236025D02*
Y216574D01*
G01Y189684D02*
Y216574D01*
G01D02*
G03X232088Y220511I-3937J0D01*
G01X236025Y216574D02*
G03X232088Y220511I-3937J0D01*
G01X243898Y224448D02*
G03X239961Y228385I-3937J0D01*
G01X237877Y996063D02*
G03Y988189I0J-3937D01*
G01Y996063D02*
G03Y988189I0J-3937D01*
G01X257284Y996063D02*
X237877D01*
G01X257284D02*
X237877D01*
G01X247835Y66929D02*
X289174D01*
G01X247836Y59055D02*
X285237D01*
G01X247836D02*
X285237D01*
G01X261220Y988189D02*
G03X265157Y992126I0J3937D01*
G01X257284Y1023622D02*
Y996063D01*
G01Y1023622D02*
Y996063D01*
G01X281019Y-508119D02*
Y-490619D01*
X278399Y-494119D01*
G01Y-508119D02*
X283639D01*
G01X293716Y-504619D02*
X295025Y-506661D01*
X296772Y-507827D01*
X298737Y-508119D01*
X300484Y-507827D01*
X302231Y-506369D01*
X303322Y-504619D01*
X303541Y-502869D01*
X303104Y-500828D01*
X301576Y-499369D01*
X300047Y-498786D01*
X298082D01*
G01X300047D02*
X301357Y-497911D01*
X302449Y-496453D01*
X302886Y-494703D01*
X302449Y-492952D01*
X301357Y-491494D01*
X299392Y-490619D01*
X297427Y-490911D01*
X295462Y-492078D01*
G01X312307Y-506078D02*
X313836Y-507536D01*
X315582Y-508119D01*
X317329Y-507536D01*
X318857Y-505786D01*
X319949Y-503161D01*
X320386Y-500536D01*
Y-497328D01*
X319949Y-494703D01*
X318857Y-492369D01*
X317547Y-491202D01*
X316019Y-490619D01*
X314272Y-491202D01*
X312962Y-492369D01*
X312089Y-494119D01*
X311652Y-496453D01*
X312089Y-498494D01*
X313181Y-500536D01*
X314491Y-501703D01*
X316019Y-501994D01*
X317765Y-501411D01*
X319076Y-499952D01*
X320386Y-497328D01*
G01X336139Y-508119D02*
Y-490619D01*
X328060Y-503161D01*
X338978D01*
G01X351019Y-508119D02*
X352547Y-507827D01*
X354294Y-506953D01*
X355386Y-505495D01*
X355822Y-503452D01*
X355386Y-501411D01*
X354076Y-499661D01*
X352111Y-498786D01*
X349927D01*
X348617Y-498202D01*
X347525Y-496744D01*
X347089Y-494703D01*
X347744Y-492661D01*
X349272Y-491202D01*
X351019Y-490619D01*
X352765Y-491202D01*
X354294Y-492661D01*
X354949Y-494703D01*
X354512Y-496744D01*
X353421Y-498202D01*
X352111Y-498786D01*
X349927D01*
X347962Y-499661D01*
X346652Y-501411D01*
X346216Y-503452D01*
X346652Y-505495D01*
X347744Y-506953D01*
X349491Y-507827D01*
X351019Y-508119D01*
G01X267902Y-463119D02*
Y-445619D01*
X273142D01*
X274889Y-446494D01*
X276199Y-448536D01*
X276636Y-450869D01*
X276199Y-453202D01*
X275107Y-454952D01*
X273142Y-455828D01*
X267902D01*
G01X294572Y-447078D02*
X293262Y-446202D01*
X291734Y-445619D01*
X289987D01*
X288022Y-446494D01*
X286494Y-447952D01*
X285402Y-449703D01*
X284529Y-452619D01*
X284310Y-455244D01*
X284747Y-457869D01*
X285402Y-459619D01*
X286712Y-461369D01*
X288241Y-462536D01*
X289769Y-463119D01*
X291297D01*
X292826Y-462536D01*
X294136Y-461661D01*
X295228Y-460495D01*
G01X309015Y-453786D02*
X309889Y-452911D01*
X310544Y-451453D01*
X310981Y-449410D01*
X310544Y-447661D01*
X309671Y-446494D01*
X308142Y-445619D01*
X302247D01*
Y-463119D01*
X309452D01*
X310981Y-461953D01*
X311854Y-460202D01*
X312291Y-458161D01*
X311854Y-456119D01*
X310544Y-454369D01*
X309015Y-453786D01*
X302247D01*
G01X318219Y-468952D02*
X331319D01*
G01X337247Y-463119D02*
Y-445619D01*
X347291Y-463119D01*
Y-445619D01*
G01X359769Y-463119D02*
X358022Y-462827D01*
X356494Y-461661D01*
X355184Y-459911D01*
X354310Y-457869D01*
X353874Y-455536D01*
Y-453202D01*
X354310Y-450869D01*
X355184Y-448827D01*
X356494Y-447078D01*
X358022Y-445911D01*
X359769Y-445619D01*
X361515Y-445911D01*
X363044Y-447078D01*
X364354Y-448827D01*
X365228Y-450869D01*
X365664Y-453202D01*
Y-455536D01*
X365228Y-457869D01*
X364354Y-459911D01*
X363044Y-461661D01*
X361515Y-462827D01*
X359769Y-463119D01*
G01X265157Y1018109D02*
Y992126D01*
G01X545472Y1018109D02*
Y1021653D01*
X543504Y1023622D01*
X267126D01*
X265157Y1021653D01*
Y1018109D01*
G01X293111Y3937D02*
G03X297047Y0I3937J0D01*
G01X293110Y62992D02*
Y3937D01*
G01X285237D02*
G03X297048Y-7874I11811J0D01*
G01X285237Y59055D02*
Y3937D01*
G01D02*
G03X297048Y-7874I11811J0D01*
G01X285237Y59055D02*
Y3937D01*
G01X293111Y62992D02*
G03X289174Y66929I-3937J0D01*
G01X297047Y0D02*
X1108209D01*
G01X297037Y-7874D02*
X301187D01*
G01D02*
G03Y0I0J3937D01*
G01X297037Y-7874D02*
X301187D01*
G01D02*
G03Y0I0J3937D01*
G01X318510Y-7874D02*
X515333D01*
G01X318510Y0D02*
G03Y-7874I0J-3937D01*
G01D02*
X515333D01*
G01X318510Y0D02*
G03Y-7874I0J-3937D01*
G01X410610Y-445619D02*
X416069Y-463119D01*
X421528Y-445619D01*
G01X437936Y-463119D02*
X429202D01*
Y-445619D01*
X437936D01*
G01X434442Y-454077D02*
X429202D01*
G01X446702Y-463119D02*
Y-445619D01*
X452161D01*
X453907Y-446494D01*
X454999Y-447661D01*
X455436Y-449994D01*
X454999Y-452328D01*
X453689Y-453786D01*
X452161Y-454661D01*
X446702D01*
G01X452161D02*
X455436Y-463119D01*
G01X468569Y-463702D02*
X468132Y-463411D01*
Y-462827D01*
X468569Y-462536D01*
X469006Y-462827D01*
Y-463411D01*
X468569Y-463702D01*
G01X433569Y-508119D02*
Y-490619D01*
X430949Y-494119D01*
G01Y-508119D02*
X436189D01*
G01X452815Y-498786D02*
X453689Y-497911D01*
X454344Y-496453D01*
X454781Y-494410D01*
X454344Y-492661D01*
X453471Y-491494D01*
X451942Y-490619D01*
X446047D01*
Y-508119D01*
X453252D01*
X454781Y-506953D01*
X455654Y-505202D01*
X456091Y-503161D01*
X455654Y-501119D01*
X454344Y-499369D01*
X452815Y-498786D01*
X446047D01*
G01X515302Y-7874D02*
G03Y0I0J3937D01*
G01Y-7874D02*
G03Y0I0J3937D01*
G01X544152Y-445619D02*
Y-463119D01*
X552886D01*
G01X569949D02*
Y-451453D01*
G01Y-453494D02*
X569076Y-452328D01*
X567765Y-451744D01*
X566237Y-451453D01*
X564709Y-452036D01*
X563399Y-453202D01*
X562525Y-454952D01*
X562089Y-457286D01*
X562525Y-459619D01*
X563399Y-461369D01*
X564709Y-462536D01*
X566237Y-463119D01*
X567765Y-462827D01*
X569076Y-461953D01*
X569949Y-460786D01*
G01X578934Y-468369D02*
X580244Y-468952D01*
X581991Y-468369D01*
X583082Y-467203D01*
X583956Y-465744D01*
X585265Y-461078D01*
X588104Y-451453D01*
G01X581117D02*
X585265Y-461078D01*
G01X597744Y-455244D02*
X604731D01*
X604076Y-453202D01*
X602984Y-452036D01*
X601456Y-451453D01*
X599927Y-451744D01*
X598617Y-452619D01*
X597744Y-454661D01*
X597307Y-456411D01*
Y-458161D01*
X597744Y-459911D01*
X598836Y-461661D01*
X600146Y-462827D01*
X601674Y-463119D01*
X603202Y-462536D01*
X604731Y-460786D01*
G01X615462Y-463119D02*
Y-451453D01*
G01Y-453786D02*
X616554Y-452619D01*
X617646Y-451744D01*
X619174Y-451453D01*
X620265Y-451744D01*
X621576Y-452619D01*
G01X540499Y-7874D02*
X727049D01*
G01X540499Y0D02*
G03Y-7874I0J-3937D01*
G01D02*
X727049D01*
G01X540499Y0D02*
G03Y-7874I0J-3937D01*
G01X545472Y994290D02*
G03X552953I3740J1D01*
G01X545472D02*
Y1018109D01*
G01X552953D02*
Y994290D01*
G01X597047Y1018109D02*
Y1021653D01*
X595078Y1023622D01*
X554921D01*
X552952Y1021653D01*
X552953Y1018109D01*
G01X597047Y992126D02*
Y1018109D01*
G01X597048Y992126D02*
G03X600984Y988189I3937J0D01*
G01X713189D02*
X600984D01*
G01X641198Y996063D02*
X604922D01*
G01D02*
Y1023622D01*
G01X641198Y996063D02*
X604922D01*
G01D02*
Y1023622D01*
G01D02*
X709253D01*
G01X604922D02*
X709253D01*
G01X641198Y988189D02*
G03Y996063I0J3937D01*
G01Y988189D02*
G03Y996063I0J3937D01*
G01X649684Y1008622D02*
G03X658266I4291J0D01*
G01D02*
G03X649684I-4291J0D01*
G01X666395Y996063D02*
G03Y988189I0J-3937D01*
G01Y996063D02*
G03Y988189I0J-3937D01*
G01X709253Y996063D02*
X666395D01*
G01X709253D02*
X666395D01*
G01X686702Y-490619D02*
Y-508119D01*
X695436D01*
G01X703984Y-513369D02*
X705294Y-513952D01*
X707041Y-513369D01*
X708132Y-512203D01*
X709006Y-510744D01*
X710315Y-506078D01*
X713154Y-496453D01*
G01X706167D02*
X710315Y-506078D01*
G01X722357Y-508119D02*
Y-496453D01*
G01Y-499369D02*
X723231Y-497911D01*
X724541Y-496744D01*
X726287Y-496453D01*
X727815Y-496744D01*
X729126Y-497911D01*
X729781Y-499952D01*
Y-508119D01*
G01X739857D02*
Y-496453D01*
G01Y-499369D02*
X740731Y-497911D01*
X742041Y-496744D01*
X743787Y-496453D01*
X745315Y-496744D01*
X746626Y-497911D01*
X747281Y-499952D01*
Y-508119D01*
G01X774202Y-490619D02*
Y-508119D01*
X782936D01*
G01X796069Y-496453D02*
Y-508119D01*
G01Y-491786D02*
X795632Y-491494D01*
Y-490911D01*
X796069Y-490619D01*
X796506Y-490911D01*
Y-491494D01*
X796069Y-491786D01*
G01X809857Y-496453D02*
Y-504619D01*
X810731Y-506661D01*
X812041Y-507827D01*
X813569Y-508119D01*
X815097Y-507827D01*
X816407Y-506661D01*
X817281Y-504619D01*
G01Y-508119D02*
Y-496453D01*
G01X686266Y-463119D02*
Y-445619D01*
X690632D01*
X692379Y-446494D01*
X693689Y-447661D01*
X694781Y-449410D01*
X695654Y-451453D01*
X695872Y-454369D01*
X695654Y-457286D01*
X694781Y-459328D01*
X693689Y-461078D01*
X692379Y-462244D01*
X690632Y-463119D01*
X686266D01*
G01X705294Y-455244D02*
X712281D01*
X711626Y-453202D01*
X710534Y-452036D01*
X709006Y-451453D01*
X707477Y-451744D01*
X706167Y-452619D01*
X705294Y-454661D01*
X704857Y-456411D01*
Y-458161D01*
X705294Y-459911D01*
X706386Y-461661D01*
X707696Y-462827D01*
X709224Y-463119D01*
X710752Y-462536D01*
X712281Y-460786D01*
G01X722794Y-461078D02*
X723886Y-462244D01*
X725414Y-463119D01*
X726724D01*
X728034Y-462536D01*
X728907Y-461661D01*
X729344Y-460495D01*
X729126Y-458744D01*
X728252Y-457869D01*
X724322Y-456119D01*
X723449Y-454077D01*
X723886Y-452619D01*
X724759Y-451744D01*
X726069Y-451453D01*
X727379Y-451744D01*
X728689Y-452619D01*
G01X743569Y-451453D02*
Y-463119D01*
G01Y-446786D02*
X743132Y-446494D01*
Y-445911D01*
X743569Y-445619D01*
X744006Y-445911D01*
Y-446494D01*
X743569Y-446786D01*
G01X758012Y-467494D02*
X759541Y-468661D01*
X761287Y-468952D01*
X762815Y-468661D01*
X764126Y-467203D01*
X764999Y-465161D01*
Y-451453D01*
G01Y-453786D02*
X764126Y-452619D01*
X762815Y-451744D01*
X761287Y-451453D01*
X759541Y-452036D01*
X758449Y-453202D01*
X757575Y-455244D01*
X757139Y-457286D01*
X757357Y-459036D01*
X758231Y-461078D01*
X759541Y-462536D01*
X761287Y-463119D01*
X762597Y-462827D01*
X764126Y-461661D01*
X764999Y-460495D01*
G01X774857Y-463119D02*
Y-451453D01*
G01Y-454369D02*
X775731Y-452911D01*
X777041Y-451744D01*
X778787Y-451453D01*
X780315Y-451744D01*
X781626Y-452911D01*
X782281Y-454952D01*
Y-463119D01*
G01X792794Y-455244D02*
X799781D01*
X799126Y-453202D01*
X798034Y-452036D01*
X796506Y-451453D01*
X794977Y-451744D01*
X793667Y-452619D01*
X792794Y-454661D01*
X792357Y-456411D01*
Y-458161D01*
X792794Y-459911D01*
X793886Y-461661D01*
X795196Y-462827D01*
X796724Y-463119D01*
X798252Y-462536D01*
X799781Y-460786D01*
G01X810512Y-463119D02*
Y-451453D01*
G01Y-453786D02*
X811604Y-452619D01*
X812696Y-451744D01*
X814224Y-451453D01*
X815315Y-451744D01*
X816626Y-452619D01*
G01X713189Y988189D02*
G03X717126Y992126I0J3937D01*
G01Y1018109D02*
Y992126D01*
G01X709253Y1023622D02*
Y996063D01*
G01Y1023622D02*
Y996063D01*
G01X745472Y1018109D02*
Y1021653D01*
X743504Y1023622D01*
X719094D01*
X717126Y1021653D01*
Y1018109D01*
G01X727049Y-7874D02*
G03Y0I0J3937D01*
G01Y-7874D02*
G03Y0I0J3937D01*
G01X752246Y-7874D02*
X984201D01*
G01X752246Y0D02*
G03Y-7874I0J-3937D01*
G01D02*
X984201D01*
G01X752246Y0D02*
G03Y-7874I0J-3937D01*
G01X745472Y994290D02*
G03X752953I3741J1D01*
G01X745472D02*
Y1018109D01*
G01X752953D02*
Y994290D01*
G01X797047Y1018109D02*
Y1021653D01*
X795078Y1023622D01*
X754921D01*
X752952Y1021653D01*
X752953Y1018109D01*
G01X797047Y992126D02*
Y1018109D01*
G01X797048Y992126D02*
G03X800984Y988189I3937J0D01*
G01X902165D02*
X800984D01*
G01X859109Y996063D02*
X804922D01*
G01D02*
Y1023622D01*
G01X859109Y996063D02*
X804922D01*
G01D02*
Y1023622D01*
G01D02*
X1325399D01*
G01X804922D02*
X1325399D01*
G01X857269Y-508119D02*
Y-490619D01*
X854649Y-494119D01*
G01Y-508119D02*
X859889D01*
G01X874769D02*
Y-490619D01*
X872149Y-494119D01*
G01Y-508119D02*
X877389D01*
G01X888339Y-508702D02*
X896199Y-490619D01*
G01X909769Y-508119D02*
Y-490619D01*
X907149Y-494119D01*
G01Y-508119D02*
X912389D01*
G01X922466Y-504619D02*
X923775Y-506661D01*
X925522Y-507827D01*
X927487Y-508119D01*
X929234Y-507827D01*
X930981Y-506369D01*
X932072Y-504619D01*
X932291Y-502869D01*
X931854Y-500828D01*
X930326Y-499369D01*
X928797Y-498786D01*
X926832D01*
G01X928797D02*
X930107Y-497911D01*
X931199Y-496453D01*
X931636Y-494703D01*
X931199Y-492952D01*
X930107Y-491494D01*
X928142Y-490619D01*
X926177Y-490911D01*
X924212Y-492078D01*
G01X940839Y-508702D02*
X948699Y-490619D01*
G01X958121Y-493536D02*
X959431Y-491786D01*
X960959Y-490911D01*
X962706Y-490619D01*
X964889Y-491202D01*
X966417Y-492661D01*
X966854Y-494410D01*
X966636Y-496161D01*
X965762Y-497619D01*
X961396Y-500536D01*
X959431Y-502577D01*
X958121Y-505495D01*
X957684Y-508119D01*
X966854D01*
G01X979769Y-490619D02*
X978022Y-491202D01*
X976712Y-492661D01*
X975839Y-494410D01*
X975184Y-496744D01*
X974966Y-499369D01*
X975184Y-501994D01*
X975839Y-504328D01*
X976712Y-506078D01*
X978022Y-507536D01*
X979769Y-508119D01*
X981515Y-507536D01*
X982826Y-506078D01*
X983699Y-504328D01*
X984354Y-501994D01*
X984572Y-499369D01*
X984354Y-496744D01*
X983699Y-494410D01*
X982826Y-492661D01*
X981515Y-491202D01*
X979769Y-490619D01*
G01X997269Y-508119D02*
Y-490619D01*
X994649Y-494119D01*
G01Y-508119D02*
X999889D01*
G01X1017389D02*
Y-490619D01*
X1009310Y-503161D01*
X1020228D01*
G01X859109Y988189D02*
G03Y996063I0J3937D01*
G01Y988189D02*
G03Y996063I0J3937D01*
G01X884306D02*
G03Y988189I0J-3937D01*
G01Y996063D02*
G03Y988189I0J-3937D01*
G01X902166Y996063D02*
X884306D01*
G01X902166D02*
X884306D01*
G01X904966Y-463119D02*
Y-445619D01*
X909332D01*
X911079Y-446494D01*
X912389Y-447661D01*
X913481Y-449410D01*
X914354Y-451453D01*
X914572Y-454369D01*
X914354Y-457286D01*
X913481Y-459328D01*
X912389Y-461078D01*
X911079Y-462244D01*
X909332Y-463119D01*
X904966D01*
G01X931199D02*
Y-451453D01*
G01Y-453494D02*
X930326Y-452328D01*
X929015Y-451744D01*
X927487Y-451453D01*
X925959Y-452036D01*
X924649Y-453202D01*
X923775Y-454952D01*
X923339Y-457286D01*
X923775Y-459619D01*
X924649Y-461369D01*
X925959Y-462536D01*
X927487Y-463119D01*
X929015Y-462827D01*
X930326Y-461953D01*
X931199Y-460786D01*
G01X944769Y-445619D02*
Y-463119D01*
G01X941712Y-451453D02*
X947826D01*
G01X958994Y-455244D02*
X965981D01*
X965326Y-453202D01*
X964234Y-452036D01*
X962706Y-451453D01*
X961177Y-451744D01*
X959867Y-452619D01*
X958994Y-454661D01*
X958557Y-456411D01*
Y-458161D01*
X958994Y-459911D01*
X960086Y-461661D01*
X961396Y-462827D01*
X962924Y-463119D01*
X964452Y-462536D01*
X965981Y-460786D01*
G01X921850Y968503D02*
G03X902165Y988189I-19685J1D01*
G01X929725Y968504D02*
G03X902166Y996063I-27559J0D01*
G01D02*
X902195D01*
G01X929725Y968504D02*
G03X902166Y996063I-27559J0D01*
G01D02*
X902195D01*
G01X921850Y775590D02*
Y968503D01*
G01Y775590D02*
G03X925787Y771653I3937J0D01*
G01X984843D02*
X925787D01*
G01X929725Y779527D02*
Y886881D01*
G01Y779527D02*
X980906D01*
G01X929725D02*
Y886881D01*
G01Y779527D02*
X980906D01*
G01X929725Y886881D02*
G03X921851I-3937J1D01*
G01X929725D02*
G03X921851I-3937J1D01*
G01Y912079D02*
G03X929725I3937J-1D01*
G01X921851D02*
G03X929725I3937J-1D01*
G01Y912078D02*
Y968504D01*
G01Y912078D02*
Y968504D01*
G01X959606Y850829D02*
G03X951024I-4291J0D01*
G01D02*
G03X959606I4291J0D01*
G01X984201Y-7874D02*
G03Y0I0J3937D01*
G01Y-7874D02*
G03Y0I0J3937D01*
G01X984843Y771653D02*
G03X988780Y775590I0J3937D01*
G01X980907Y886881D02*
X980906Y779527D01*
G01X980907Y886881D02*
X980906Y779527D01*
G01X988781Y886881D02*
G03X980907I-3937J1D01*
G01X988781D02*
G03X980907I-3937J1D01*
G01Y912079D02*
G03X988781I3937J-1D01*
G01X980907D02*
G03X988781I3937J-1D01*
G01X980907D02*
X980906Y968504D01*
G01X980907Y912079D02*
X980906Y968504D01*
G01X1008465Y996063D02*
G03X980906Y968504I0J-27559D01*
G01X1008465Y996063D02*
G03X980906Y968504I0J-27559D01*
G01X988780Y968503D02*
Y775590D01*
G01X1008465Y988189D02*
G03X988780Y968503I0J-19685D01*
G01X1009398Y-7874D02*
X1108229D01*
G01X1009398Y0D02*
G03Y-7874I-1J-3937D01*
G01D02*
X1108229D01*
G01X1009398Y0D02*
G03Y-7874I-1J-3937D01*
G01X1380315Y988189D02*
X1008465D01*
G01X1070592Y996063D02*
X1008466D01*
G01X1070592D02*
X1008466D01*
G01X1070592Y988189D02*
G03Y996063I0J3937D01*
G01Y988189D02*
G03Y996063I0J3937D01*
G01X1095789D02*
G03Y988189I0J-3937D01*
G01Y996063D02*
G03Y988189I0J-3937D01*
G01X1325399Y996063D02*
X1095789D01*
G01X1325399D02*
X1095789D01*
G01X1112146Y3937D02*
Y210629D01*
G01X1108209Y0D02*
G03X1112146Y3937I0J3937D01*
G01X1108208Y-7874D02*
G03X1120020Y3938I1J11811D01*
G01X1108208Y-7874D02*
G03X1120020Y3938I1J11811D01*
G01Y99950D02*
G03X1112146I-3937J0D01*
G01X1120020D02*
G03X1112146I-3937J0D01*
G01Y125147D02*
G03X1120020I3937J0D01*
G01X1112146D02*
G03X1120020I3937J0D01*
G01X1116083Y214566D02*
X1194824D01*
G01X1116083D02*
G03X1112146Y210629I0J-3937D01*
G01X1120020Y99950D02*
Y3938D01*
G01Y99950D02*
Y3938D01*
G01Y125147D02*
Y206693D01*
G01Y125147D02*
Y206693D01*
G01X1120021D02*
X1190887D01*
G01X1120021D02*
X1190887D01*
G01X1161386Y128841D02*
G03X1152804I-4291J0D01*
G01D02*
G03X1161386I4291J0D01*
G01X1198760Y3937D02*
G03X1210571Y-7874I11811J0D01*
G01X1198760Y3937D02*
G03X1210571Y-7874I11811J0D01*
G01X1198761Y97100D02*
X1198760Y3937D01*
G01X1198761Y97100D02*
X1198760Y3937D01*
G01X1206635Y97100D02*
G03X1198761I-3937J0D01*
G01X1206635D02*
G03X1198761I-3937J0D01*
G01Y122297D02*
G03X1206635I3937J0D01*
G01X1198761D02*
G03X1206635I3937J0D01*
G01X1198761D02*
Y168002D01*
G01Y122297D02*
Y168002D01*
G01X1190887Y179134D02*
G03X1198761Y167998I11811J0D01*
G01X1190887Y179134D02*
G03X1198761Y167998I11811J0D01*
G01X1198760Y179133D02*
G03X1202697Y175196I3937J0D01*
G01X1198760Y210629D02*
Y179133D01*
G01X1190887Y206693D02*
Y179134D01*
G01Y206693D02*
Y179134D01*
G01X1198760Y210629D02*
G03X1194824Y214566I-3937J0D01*
G01X1210571Y0D02*
X1396063D01*
G01X1206634Y3937D02*
G03X1210571Y0I3937J0D01*
G01X1206634Y171259D02*
Y3937D01*
G01X1210552Y-7874D02*
X1210572D01*
G01D02*
G03Y0I0J3937D01*
G01X1210552Y-7874D02*
X1210572D01*
G01D02*
G03Y0I0J3937D01*
G01X1206634Y171259D02*
G03X1202697Y175196I-3937J0D01*
G01X1226320Y-7874D02*
X1380317D01*
G01X1226320Y0D02*
G03Y-7874I0J-3937D01*
G01D02*
X1380317D01*
G01X1226320Y0D02*
G03Y-7874I0J-3937D01*
G01X1354801Y996063D02*
X1325399D01*
G01X1354801D02*
X1325399D01*
G01Y1023622D02*
X1385001D01*
G01X1325399D02*
X1385001D01*
G01X1354801Y988189D02*
G03Y996063I0J3937D01*
G01Y988189D02*
G03Y996063I0J3937D01*
G01X1380316Y-7874D02*
G03Y0I0J3937D01*
G01Y-7874D02*
G03Y0I0J3937D01*
G01X1400000Y968503D02*
G03X1380315Y988189I-19685J1D01*
G01X1379998Y996063D02*
G03Y988189I0J-3937D01*
G01Y996063D02*
G03Y988189I0J-3937D01*
G01X1400001Y996063D02*
X1379998D01*
G01X1400001D02*
X1379998D01*
G01X1392127Y-25591D02*
G03X1400001Y-17717I0J7874D01*
G01X1392167Y-15015D02*
G03X1383585I-4291J0D01*
G01D02*
G03X1392167I4291J0D01*
G01X1392127Y-25591D02*
G03X1400001Y-17717I0J7874D01*
G01X1396063Y0D02*
G03X1400000Y3937I0J3937D01*
G01X1396064Y-7874D02*
X1400001D01*
G01X1396064Y0D02*
G03Y-7874I0J-3937D01*
G01D02*
X1400001D01*
G01X1396064Y0D02*
G03Y-7874I0J-3937D01*
G01X1380710Y1008622D02*
G03X1389292I4291J0D01*
G01D02*
G03X1380710I-4291J0D01*
G01X1400001D02*
G03X1385001Y1023622I-15000J0D01*
G01X1400001Y1008622D02*
G03X1385001Y1023622I-15000J0D01*
G01X1400001Y-17717D02*
Y-7874D01*
G01Y-17717D02*
Y-7874D01*
G01X1400000Y3937D02*
Y968503D01*
G01X1400001Y996063D02*
Y1008622D01*
G01Y996063D02*
Y1008622D01*
G01X115500Y368000D02*
X117500D01*
G01X116500D02*
Y363000D01*
G01X115500D02*
X117500D01*
G01X122100D02*
X121433Y363083D01*
X120850Y363417D01*
X120350Y363917D01*
X120017Y364500D01*
X119850Y365167D01*
Y365833D01*
X120017Y366500D01*
X120350Y367083D01*
X120850Y367583D01*
X121433Y367917D01*
X122100Y368000D01*
X122767Y367917D01*
X123350Y367583D01*
X123850Y367083D01*
X124183Y366500D01*
X124350Y365833D01*
Y365167D01*
X124183Y364500D01*
X123850Y363917D01*
X123350Y363417D01*
X122767Y363083D01*
X122100Y363000D01*
G01X129533Y367583D02*
X129033Y367833D01*
X128450Y368000D01*
X127783D01*
X127033Y367750D01*
X126450Y367333D01*
X126033Y366833D01*
X125700Y366000D01*
X125617Y365250D01*
X125783Y364500D01*
X126033Y364000D01*
X126533Y363500D01*
X127117Y363167D01*
X127700Y363000D01*
X128283D01*
X128867Y363167D01*
X129367Y363417D01*
X129783Y363750D01*
G01X185167Y328500D02*
X181833D01*
Y333500D01*
X185167D01*
G01X183833Y331083D02*
X181833D01*
G01X187350Y328500D02*
X190850Y333500D01*
G01X187350D02*
X190850Y328500D01*
G01X193033D02*
Y333500D01*
X195033D01*
X195700Y333250D01*
X196200Y332667D01*
X196367Y332000D01*
X196200Y331333D01*
X195783Y330833D01*
X195033Y330583D01*
X193033D01*
G01X1344833Y41500D02*
Y46500D01*
X1346833D01*
X1347500Y46250D01*
X1348000Y45667D01*
X1348167Y45000D01*
X1348000Y44333D01*
X1347583Y43833D01*
X1346833Y43583D01*
X1344833D01*
G01X1349600Y46500D02*
X1350767Y41500D01*
X1352100Y46500D01*
X1353433Y41500D01*
X1354600Y46500D01*
G01X1356033Y41500D02*
Y46500D01*
X1358117D01*
X1358783Y46250D01*
X1359200Y45917D01*
X1359367Y45250D01*
X1359200Y44583D01*
X1358700Y44167D01*
X1358117Y43917D01*
X1356033D01*
G01X1358117D02*
X1359367Y41500D01*
G01X1344833Y67500D02*
Y72500D01*
X1346917D01*
X1347583Y72250D01*
X1348000Y71917D01*
X1348167Y71250D01*
X1348000Y70583D01*
X1347500Y70167D01*
X1346917Y69917D01*
X1344833D01*
G01X1346917D02*
X1348167Y67500D01*
G01X1350350Y68167D02*
X1351017Y67750D01*
X1351767Y67500D01*
X1352433D01*
X1353100Y67750D01*
X1353600Y68167D01*
X1353850Y68750D01*
X1353683Y69333D01*
X1353267Y69833D01*
X1352517Y70167D01*
X1351517Y70333D01*
X1350933Y70667D01*
X1350683Y71250D01*
X1350850Y71833D01*
X1351267Y72250D01*
X1351850Y72500D01*
X1352433D01*
X1353017Y72333D01*
X1353517Y71917D01*
G01X1357700Y72500D02*
Y67500D01*
G01X1355783Y72500D02*
X1359617D01*
G54D12*
G01X310467Y654500D02*
Y664500D01*
X314633D01*
X315967Y664000D01*
X316800Y663333D01*
X317133Y662000D01*
X316800Y660667D01*
X315800Y659833D01*
X314633Y659333D01*
X310467D01*
G01X314633D02*
X317133Y654500D01*
G01X324600D02*
X323266Y654667D01*
X322100Y655333D01*
X321100Y656333D01*
X320433Y657500D01*
X320100Y658833D01*
Y660167D01*
X320433Y661500D01*
X321100Y662667D01*
X322100Y663667D01*
X323266Y664333D01*
X324600Y664500D01*
X325933Y664333D01*
X327100Y663667D01*
X328100Y662667D01*
X328767Y661500D01*
X329100Y660167D01*
Y658833D01*
X328767Y657500D01*
X328100Y656333D01*
X327100Y655333D01*
X325933Y654667D01*
X324600Y654500D01*
G01X331900D02*
Y664500D01*
G01X338900D02*
Y654500D01*
G01Y659500D02*
X331900D01*
G01X342700Y655833D02*
X344033Y655000D01*
X345533Y654500D01*
X346867D01*
X348200Y655000D01*
X349200Y655833D01*
X349700Y657000D01*
X349367Y658166D01*
X348533Y659167D01*
X347033Y659833D01*
X345033Y660167D01*
X343867Y660833D01*
X343367Y662000D01*
X343700Y663167D01*
X344533Y664000D01*
X345700Y664500D01*
X346867D01*
X348033Y664167D01*
X349033Y663333D01*
G01X371467Y663667D02*
X370467Y664167D01*
X369300Y664500D01*
X367967D01*
X366466Y664000D01*
X365300Y663167D01*
X364467Y662167D01*
X363800Y660500D01*
X363633Y659000D01*
X363967Y657500D01*
X364467Y656500D01*
X365467Y655500D01*
X366633Y654833D01*
X367800Y654500D01*
X368967D01*
X370133Y654833D01*
X371133Y655333D01*
X371967Y656000D01*
G01X378600Y654500D02*
X377600Y654667D01*
X376600Y655333D01*
X375933Y656500D01*
X375600Y657833D01*
X375933Y659167D01*
X376600Y660333D01*
X377600Y661000D01*
X378600Y661166D01*
X379600Y661000D01*
X380600Y660333D01*
X381267Y659167D01*
X381433Y657833D01*
X381267Y656500D01*
X380600Y655333D01*
X379600Y654667D01*
X378600Y654500D01*
G01X384400D02*
Y661166D01*
G01Y659333D02*
X384900Y660167D01*
X385733Y660833D01*
X386900Y661166D01*
X388066Y660833D01*
X388900Y660167D01*
X389400Y659333D01*
Y654500D01*
G01Y659333D02*
X389900Y660167D01*
X390733Y660833D01*
X391900Y661166D01*
X393067Y660833D01*
X393900Y660167D01*
X394400Y659167D01*
Y654500D01*
G01X397200Y651167D02*
Y661166D01*
G01Y659667D02*
X398033Y660500D01*
X398866Y661000D01*
X400200Y661166D01*
X401367Y661000D01*
X402533Y660167D01*
X403033Y659000D01*
X403200Y657833D01*
X403033Y656667D01*
X402533Y655500D01*
X401533Y654833D01*
X400200Y654500D01*
X399033Y654667D01*
X397867Y655167D01*
X397200Y655833D01*
G01X411000Y654500D02*
Y664500D01*
G01X421800Y661166D02*
Y654500D01*
G01Y663833D02*
X421467Y664000D01*
Y664333D01*
X421800Y664500D01*
X422133Y664333D01*
Y664000D01*
X421800Y663833D01*
G01X435600Y654500D02*
Y661166D01*
G01Y660000D02*
X434933Y660667D01*
X433933Y661000D01*
X432767Y661166D01*
X431600Y660833D01*
X430600Y660167D01*
X429933Y659167D01*
X429600Y657833D01*
X429933Y656500D01*
X430600Y655500D01*
X431600Y654833D01*
X432767Y654500D01*
X433933Y654667D01*
X434933Y655167D01*
X435600Y655833D01*
G01X440567Y654500D02*
Y661166D01*
G01Y659500D02*
X441233Y660333D01*
X442233Y661000D01*
X443567Y661166D01*
X444733Y661000D01*
X445733Y660333D01*
X446233Y659167D01*
Y654500D01*
G01X456867Y660333D02*
X455700Y661000D01*
X454700Y661166D01*
X453367Y660833D01*
X452367Y660167D01*
X451700Y659000D01*
X451533Y657833D01*
X451700Y656667D01*
X452367Y655666D01*
X453367Y654833D01*
X454700Y654500D01*
X455867Y654833D01*
X456867Y655500D01*
G01X462500Y659000D02*
X467833D01*
X467333Y660167D01*
X466500Y660833D01*
X465333Y661166D01*
X464167Y661000D01*
X463167Y660500D01*
X462500Y659333D01*
X462167Y658333D01*
Y657333D01*
X462500Y656333D01*
X463333Y655333D01*
X464333Y654667D01*
X465500Y654500D01*
X466667Y654833D01*
X467833Y655833D01*
G01X447333Y21000D02*
Y16000D01*
X450667D01*
G01X456267D02*
X452933D01*
Y21000D01*
X456267D01*
G01X454933Y18583D02*
X452933D01*
G01X458367Y16000D02*
Y21000D01*
X460033D01*
X460700Y20750D01*
X461200Y20417D01*
X461617Y19917D01*
X461950Y19333D01*
X462033Y18500D01*
X461950Y17667D01*
X461617Y17083D01*
X461200Y16583D01*
X460700Y16250D01*
X460033Y16000D01*
X458367D01*
G01X463967Y16750D02*
X464467Y16333D01*
X465050Y16083D01*
X465800Y16000D01*
X466550Y16167D01*
X467133Y16500D01*
X467550Y17083D01*
X467633Y17750D01*
X467467Y18417D01*
X467050Y18833D01*
X466467Y19167D01*
X465883Y19250D01*
X465300Y19167D01*
X464550Y18833D01*
X464800Y21000D01*
X467050D01*
G01X471400Y15833D02*
X471233Y15917D01*
Y16083D01*
X471400Y16167D01*
X471567Y16083D01*
Y15917D01*
X471400Y15833D01*
G01Y18083D02*
X471233Y18167D01*
Y18333D01*
X471400Y18417D01*
X471567Y18333D01*
Y18167D01*
X471400Y18083D01*
G01X475333Y16000D02*
Y21000D01*
X477333D01*
X478000Y20750D01*
X478500Y20167D01*
X478667Y19500D01*
X478500Y18833D01*
X478083Y18333D01*
X477333Y18083D01*
X475333D01*
G01X480100Y21000D02*
X481267Y16000D01*
X482600Y21000D01*
X483933Y16000D01*
X485100Y21000D01*
G01X486533Y16000D02*
Y21000D01*
X488617D01*
X489283Y20750D01*
X489700Y20417D01*
X489867Y19750D01*
X489700Y19083D01*
X489200Y18667D01*
X488617Y18417D01*
X486533D01*
G01X488617D02*
X489867Y16000D01*
G01X501900Y14333D02*
X497733Y19333D01*
Y20167D01*
X498567Y21000D01*
X499400D01*
X500233Y20167D01*
Y19333D01*
X499400Y18500D01*
X497733Y17667D01*
X496900Y16833D01*
Y15167D01*
X497733Y14333D01*
X500233D01*
X501900Y16000D01*
G01X509600Y21000D02*
X511600D01*
G01X510600D02*
Y16000D01*
G01X509600D02*
X511600D01*
G01X514367D02*
Y21000D01*
X516033D01*
X516700Y20750D01*
X517200Y20417D01*
X517617Y19917D01*
X517950Y19333D01*
X518033Y18500D01*
X517950Y17667D01*
X517617Y17083D01*
X517200Y16583D01*
X516700Y16250D01*
X516033Y16000D01*
X514367D01*
G01X525733Y21000D02*
Y16000D01*
X529067D01*
G01X534667D02*
X531333D01*
Y21000D01*
X534667D01*
G01X533333Y18583D02*
X531333D01*
G01X536767Y16000D02*
Y21000D01*
X538433D01*
X539100Y20750D01*
X539600Y20417D01*
X540017Y19917D01*
X540350Y19333D01*
X540433Y18500D01*
X540350Y17667D01*
X540017Y17083D01*
X539600Y16583D01*
X539100Y16250D01*
X538433Y16000D01*
X536767D01*
G01X447333Y31000D02*
Y26000D01*
X450667D01*
G01X456267D02*
X452933D01*
Y31000D01*
X456267D01*
G01X454933Y28583D02*
X452933D01*
G01X458367Y26000D02*
Y31000D01*
X460033D01*
X460700Y30750D01*
X461200Y30417D01*
X461617Y29917D01*
X461950Y29333D01*
X462033Y28500D01*
X461950Y27667D01*
X461617Y27083D01*
X461200Y26583D01*
X460700Y26250D01*
X460033Y26000D01*
X458367D01*
G01X466800D02*
Y31000D01*
X463717Y27417D01*
X467883D01*
G01X471400Y25833D02*
X471233Y25917D01*
Y26083D01*
X471400Y26167D01*
X471567Y26083D01*
Y25917D01*
X471400Y25833D01*
G01Y28083D02*
X471233Y28167D01*
Y28333D01*
X471400Y28417D01*
X471567Y28333D01*
Y28167D01*
X471400Y28083D01*
G01X478667Y26000D02*
X475333D01*
Y31000D01*
X478667D01*
G01X477333Y28583D02*
X475333D01*
G01X481183Y26000D02*
Y29333D01*
G01Y28500D02*
X481517Y28917D01*
X482017Y29250D01*
X482683Y29333D01*
X483267Y29250D01*
X483767Y28917D01*
X484017Y28333D01*
Y26000D01*
G01X489533Y28917D02*
X488950Y29250D01*
X488450Y29333D01*
X487783Y29167D01*
X487283Y28833D01*
X486950Y28250D01*
X486867Y27667D01*
X486950Y27083D01*
X487283Y26583D01*
X487783Y26167D01*
X488450Y26000D01*
X489033Y26167D01*
X489533Y26500D01*
G01X493800Y26000D02*
Y31000D01*
G01X499400Y26000D02*
X498900Y26083D01*
X498400Y26417D01*
X498067Y27000D01*
X497900Y27667D01*
X498067Y28333D01*
X498400Y28917D01*
X498900Y29250D01*
X499400Y29333D01*
X499900Y29250D01*
X500400Y28917D01*
X500733Y28333D01*
X500817Y27667D01*
X500733Y27000D01*
X500400Y26417D01*
X499900Y26083D01*
X499400Y26000D01*
G01X503750Y26583D02*
X504167Y26250D01*
X504750Y26000D01*
X505250D01*
X505750Y26167D01*
X506083Y26417D01*
X506250Y26750D01*
X506167Y27250D01*
X505833Y27500D01*
X504333Y28000D01*
X504000Y28583D01*
X504167Y29000D01*
X504500Y29250D01*
X505000Y29333D01*
X505500Y29250D01*
X506000Y29000D01*
G01X509183Y29333D02*
Y27000D01*
X509517Y26417D01*
X510017Y26083D01*
X510600Y26000D01*
X511183Y26083D01*
X511683Y26417D01*
X512017Y27000D01*
G01Y26000D02*
Y29333D01*
G01X515033Y26000D02*
Y29333D01*
G01Y28667D02*
X515450Y29000D01*
X515867Y29250D01*
X516450Y29333D01*
X516867Y29250D01*
X517367Y29000D01*
G01X520550Y28250D02*
X523217D01*
X522967Y28833D01*
X522550Y29167D01*
X521967Y29333D01*
X521383Y29250D01*
X520883Y29000D01*
X520550Y28417D01*
X520383Y27917D01*
Y27417D01*
X520550Y26917D01*
X520967Y26417D01*
X521467Y26083D01*
X522050Y26000D01*
X522633Y26167D01*
X523217Y26667D01*
G01X531333Y31000D02*
Y26000D01*
X534667D01*
G01X540267D02*
X536933D01*
Y31000D01*
X540267D01*
G01X538933Y28583D02*
X536933D01*
G01X542367Y26000D02*
Y31000D01*
X544033D01*
X544700Y30750D01*
X545200Y30417D01*
X545617Y29917D01*
X545950Y29333D01*
X546033Y28500D01*
X545950Y27667D01*
X545617Y27083D01*
X545200Y26583D01*
X544700Y26250D01*
X544033Y26000D01*
X542367D01*
G01X858000Y31100D02*
X862666Y11100D01*
X868000Y31100D01*
X873333Y11100D01*
X878000Y31100D01*
G01X888800Y24433D02*
Y11100D01*
G01Y29766D02*
X888133Y30100D01*
Y30767D01*
X888800Y31100D01*
X889467Y30767D01*
Y30100D01*
X888800Y29766D01*
G01X901266Y24433D02*
X905267Y11100D01*
X909600Y24433D01*
X913933Y11100D01*
X917934Y24433D01*
G01X923400Y5100D02*
X925400Y4434D01*
X928067Y5100D01*
X929733Y6433D01*
X931067Y8100D01*
X933066Y13433D01*
X937400Y24433D01*
G01X926733D02*
X933066Y13433D01*
G01X945533Y11100D02*
Y24433D01*
G01Y21100D02*
X946867Y22767D01*
X948867Y24100D01*
X951534Y24433D01*
X953866Y24100D01*
X955867Y22767D01*
X956867Y20433D01*
Y11100D01*
G01X966333D02*
Y24433D01*
G01Y21100D02*
X967667Y22767D01*
X969667Y24100D01*
X972334Y24433D01*
X974666Y24100D01*
X976667Y22767D01*
X977667Y20433D01*
Y11100D01*
G01X1215000Y12000D02*
Y17000D01*
X1214000Y16000D01*
G01Y12000D02*
X1216000D01*
G01X1215000Y22500D02*
Y27500D01*
X1214000Y26500D01*
G01Y22500D02*
X1216000D01*
G01X1210000Y30500D02*
Y8500D01*
X1252000D01*
Y30500D01*
G01X1210000Y19500D02*
X1252000D01*
G01X1215000Y39000D02*
X1214333Y38833D01*
X1213833Y38417D01*
X1213500Y37917D01*
X1213250Y37250D01*
X1213167Y36500D01*
X1213250Y35750D01*
X1213500Y35083D01*
X1213833Y34583D01*
X1214333Y34167D01*
X1215000Y34000D01*
X1215667Y34167D01*
X1216167Y34583D01*
X1216500Y35083D01*
X1216750Y35750D01*
X1216833Y36500D01*
X1216750Y37250D01*
X1216500Y37917D01*
X1216167Y38417D01*
X1215667Y38833D01*
X1215000Y39000D01*
G01X1210000Y53500D02*
Y30500D01*
X1252000D01*
Y53500D01*
G01X1213250Y56000D02*
Y61000D01*
G01X1216750D02*
Y56000D01*
G01Y58500D02*
X1213250D01*
G01X1215000Y49500D02*
X1214333Y49333D01*
X1213833Y48917D01*
X1213500Y48417D01*
X1213250Y47750D01*
X1213167Y47000D01*
X1213250Y46250D01*
X1213500Y45583D01*
X1213833Y45083D01*
X1214333Y44667D01*
X1215000Y44500D01*
X1215667Y44667D01*
X1216167Y45083D01*
X1216500Y45583D01*
X1216750Y46250D01*
X1216833Y47000D01*
X1216750Y47750D01*
X1216500Y48417D01*
X1216167Y48917D01*
X1215667Y49333D01*
X1215000Y49500D01*
G01X1252000Y63500D02*
Y53500D01*
X1210000D01*
Y63500D01*
X1252000D01*
G01X1210000Y41500D02*
X1252000D01*
G01X1219333Y75983D02*
X1218833Y76233D01*
X1218250Y76400D01*
X1217583D01*
X1216833Y76150D01*
X1216250Y75733D01*
X1215833Y75233D01*
X1215500Y74400D01*
X1215417Y73650D01*
X1215583Y72900D01*
X1215833Y72400D01*
X1216333Y71900D01*
X1216917Y71567D01*
X1217500Y71400D01*
X1218083D01*
X1218667Y71567D01*
X1219167Y71817D01*
X1219583Y72150D01*
G01X1221433Y71400D02*
Y76400D01*
X1223433D01*
X1224100Y76150D01*
X1224600Y75567D01*
X1224767Y74900D01*
X1224600Y74233D01*
X1224183Y73733D01*
X1223433Y73483D01*
X1221433D01*
G01X1226867Y76400D02*
Y72817D01*
X1227200Y72067D01*
X1227867Y71567D01*
X1228700Y71400D01*
X1229533Y71567D01*
X1230200Y72067D01*
X1230533Y72817D01*
Y76400D01*
G01X1214000Y105500D02*
X1265000D01*
Y68000D01*
X1210000D01*
Y105500D01*
X1214000D01*
G01X1217500Y83800D02*
Y88800D01*
X1216500Y87800D01*
G01Y83800D02*
X1218500D01*
G01X1222017Y85467D02*
X1224183D01*
G01X1227117Y87967D02*
X1227617Y88467D01*
X1228200Y88717D01*
X1228867Y88800D01*
X1229700Y88633D01*
X1230283Y88217D01*
X1230450Y87717D01*
X1230367Y87217D01*
X1230033Y86800D01*
X1228367Y85967D01*
X1227617Y85383D01*
X1227117Y84550D01*
X1226950Y83800D01*
X1230450D01*
G01X1265000Y80500D02*
X1210000D01*
G01X1213167Y97000D02*
Y102000D01*
X1214833D01*
X1215500Y101750D01*
X1216000Y101417D01*
X1216417Y100917D01*
X1216750Y100333D01*
X1216833Y99500D01*
X1216750Y98667D01*
X1216417Y98083D01*
X1216000Y97583D01*
X1215500Y97250D01*
X1214833Y97000D01*
X1213167D01*
G01X1219350Y99250D02*
X1222017D01*
X1221767Y99833D01*
X1221350Y100167D01*
X1220767Y100333D01*
X1220183Y100250D01*
X1219683Y100000D01*
X1219350Y99417D01*
X1219183Y98917D01*
Y98417D01*
X1219350Y97917D01*
X1219767Y97417D01*
X1220267Y97083D01*
X1220850Y97000D01*
X1221433Y97167D01*
X1222017Y97667D01*
G01X1224700Y97000D02*
Y102000D01*
G01Y99500D02*
X1225117Y100000D01*
X1225617Y100250D01*
X1226117Y100333D01*
X1226867Y100167D01*
X1227367Y99833D01*
X1227700Y99250D01*
Y98583D01*
X1227533Y97917D01*
X1227200Y97417D01*
X1226617Y97083D01*
X1226117Y97000D01*
X1225617Y97083D01*
X1225117Y97333D01*
X1224700Y97750D01*
G01X1230383Y100333D02*
Y98000D01*
X1230717Y97417D01*
X1231217Y97083D01*
X1231800Y97000D01*
X1232383Y97083D01*
X1232883Y97417D01*
X1233217Y98000D01*
G01Y97000D02*
Y100333D01*
G01X1236233Y95750D02*
X1236817Y95417D01*
X1237483Y95333D01*
X1238067Y95417D01*
X1238567Y95833D01*
X1238900Y96417D01*
Y100333D01*
G01Y99667D02*
X1238567Y100000D01*
X1238067Y100250D01*
X1237483Y100333D01*
X1236817Y100167D01*
X1236400Y99833D01*
X1236067Y99250D01*
X1235900Y98667D01*
X1235983Y98167D01*
X1236317Y97583D01*
X1236817Y97167D01*
X1237483Y97000D01*
X1237983Y97083D01*
X1238567Y97417D01*
X1238900Y97750D01*
G01X1246933Y102000D02*
Y97000D01*
X1250267D01*
G01X1255867D02*
X1252533D01*
Y102000D01*
X1255867D01*
G01X1254533Y99583D02*
X1252533D01*
G01X1257967Y97000D02*
Y102000D01*
X1259633D01*
X1260300Y101750D01*
X1260800Y101417D01*
X1261217Y100917D01*
X1261550Y100333D01*
X1261633Y99500D01*
X1261550Y98667D01*
X1261217Y98083D01*
X1260800Y97583D01*
X1260300Y97250D01*
X1259633Y97000D01*
X1257967D01*
G01X1210500Y92500D02*
X1265000D01*
G01X1225000Y12000D02*
Y17000D01*
X1224000Y16000D01*
G01Y12000D02*
X1226000D01*
G01X1225000Y27500D02*
X1224333Y27333D01*
X1223833Y26917D01*
X1223500Y26417D01*
X1223250Y25750D01*
X1223167Y25000D01*
X1223250Y24250D01*
X1223500Y23583D01*
X1223833Y23083D01*
X1224333Y22667D01*
X1225000Y22500D01*
X1225667Y22667D01*
X1226167Y23083D01*
X1226500Y23583D01*
X1226750Y24250D01*
X1226833Y25000D01*
X1226750Y25750D01*
X1226500Y26417D01*
X1226167Y26917D01*
X1225667Y27333D01*
X1225000Y27500D01*
G01X1236667Y12000D02*
X1233333D01*
Y17000D01*
X1236667D01*
G01X1235333Y14583D02*
X1233333D01*
G01X1238850Y12000D02*
X1242350Y17000D01*
G01X1238850D02*
X1242350Y12000D01*
G01X1244533D02*
Y17000D01*
X1246533D01*
X1247200Y16750D01*
X1247700Y16167D01*
X1247867Y15500D01*
X1247700Y14833D01*
X1247283Y14333D01*
X1246533Y14083D01*
X1244533D01*
G01X1234000Y27500D02*
X1236000D01*
G01X1235000D02*
Y22500D01*
G01X1234000D02*
X1236000D01*
G01X1240600D02*
X1239933Y22583D01*
X1239350Y22917D01*
X1238850Y23417D01*
X1238517Y24000D01*
X1238350Y24667D01*
Y25333D01*
X1238517Y26000D01*
X1238850Y26583D01*
X1239350Y27083D01*
X1239933Y27417D01*
X1240600Y27500D01*
X1241267Y27417D01*
X1241850Y27083D01*
X1242350Y26583D01*
X1242683Y26000D01*
X1242850Y25333D01*
Y24667D01*
X1242683Y24000D01*
X1242350Y23417D01*
X1241850Y22917D01*
X1241267Y22583D01*
X1240600Y22500D01*
G01X1248033Y27083D02*
X1247533Y27333D01*
X1246950Y27500D01*
X1246283D01*
X1245533Y27250D01*
X1244950Y26833D01*
X1244533Y26333D01*
X1244200Y25500D01*
X1244117Y24750D01*
X1244283Y24000D01*
X1244533Y23500D01*
X1245033Y23000D01*
X1245617Y22667D01*
X1246200Y22500D01*
X1246783D01*
X1247367Y22667D01*
X1247867Y22917D01*
X1248283Y23250D01*
G01X1220000Y63500D02*
Y8500D01*
G01X1230000Y63500D02*
Y8500D01*
G01X1225000Y34000D02*
Y39000D01*
X1224000Y38000D01*
G01Y34000D02*
X1226000D01*
G01X1235667Y36667D02*
X1236000Y36917D01*
X1236250Y37333D01*
X1236417Y37917D01*
X1236250Y38417D01*
X1235917Y38750D01*
X1235333Y39000D01*
X1233083D01*
Y34000D01*
X1235833D01*
X1236417Y34333D01*
X1236750Y34833D01*
X1236917Y35417D01*
X1236750Y36000D01*
X1236250Y36500D01*
X1235667Y36667D01*
X1233083D01*
G01X1238433Y34000D02*
Y39000D01*
X1240600Y34833D01*
X1242767Y39000D01*
Y34000D01*
G01X1248033Y38583D02*
X1247533Y38833D01*
X1246950Y39000D01*
X1246283D01*
X1245533Y38750D01*
X1244950Y38333D01*
X1244533Y37833D01*
X1244200Y37000D01*
X1244117Y36250D01*
X1244283Y35500D01*
X1244533Y35000D01*
X1245033Y34500D01*
X1245617Y34167D01*
X1246200Y34000D01*
X1246783D01*
X1247367Y34167D01*
X1247867Y34417D01*
X1248283Y34750D01*
G01X1223333Y61000D02*
Y56000D01*
X1226667D01*
G01X1225000Y49500D02*
X1224333Y49333D01*
X1223833Y48917D01*
X1223500Y48417D01*
X1223250Y47750D01*
X1223167Y47000D01*
X1223250Y46250D01*
X1223500Y45583D01*
X1223833Y45083D01*
X1224333Y44667D01*
X1225000Y44500D01*
X1225667Y44667D01*
X1226167Y45083D01*
X1226500Y45583D01*
X1226750Y46250D01*
X1226833Y47000D01*
X1226750Y47750D01*
X1226500Y48417D01*
X1226167Y48917D01*
X1225667Y49333D01*
X1225000Y49500D01*
G01X1236833Y49083D02*
X1236333Y49333D01*
X1235750Y49500D01*
X1235083D01*
X1234333Y49250D01*
X1233750Y48833D01*
X1233333Y48333D01*
X1233000Y47500D01*
X1232917Y46750D01*
X1233083Y46000D01*
X1233333Y45500D01*
X1233833Y45000D01*
X1234417Y44667D01*
X1235000Y44500D01*
X1235583D01*
X1236167Y44667D01*
X1236667Y44917D01*
X1237083Y45250D01*
G01X1238933Y44500D02*
Y49500D01*
X1240933D01*
X1241600Y49250D01*
X1242100Y48667D01*
X1242267Y48000D01*
X1242100Y47333D01*
X1241683Y46833D01*
X1240933Y46583D01*
X1238933D01*
G01X1244367Y49500D02*
Y45917D01*
X1244700Y45167D01*
X1245367Y44667D01*
X1246200Y44500D01*
X1247033Y44667D01*
X1247700Y45167D01*
X1248033Y45917D01*
Y49500D01*
G01X1234167Y61000D02*
Y57417D01*
X1234500Y56667D01*
X1235167Y56167D01*
X1236000Y56000D01*
X1236833Y56167D01*
X1237500Y56667D01*
X1237833Y57417D01*
Y61000D01*
G01X1239933Y56000D02*
Y61000D01*
X1242017D01*
X1242683Y60750D01*
X1243100Y60417D01*
X1243267Y59750D01*
X1243100Y59083D01*
X1242600Y58667D01*
X1242017Y58417D01*
X1239933D01*
G01X1242017D02*
X1243267Y56000D01*
G01X1245667Y71400D02*
X1242333D01*
Y76400D01*
X1245667D01*
G01X1244333Y73983D02*
X1242333D01*
G01X1247850Y71400D02*
X1251350Y76400D01*
G01X1247850D02*
X1251350Y71400D01*
G01X1253533D02*
Y76400D01*
X1255533D01*
X1256200Y76150D01*
X1256700Y75567D01*
X1256867Y74900D01*
X1256700Y74233D01*
X1256283Y73733D01*
X1255533Y73483D01*
X1253533D01*
G01X1237000Y92500D02*
Y68000D01*
G01X1242417Y87967D02*
X1242917Y88467D01*
X1243500Y88717D01*
X1244167Y88800D01*
X1245000Y88633D01*
X1245583Y88217D01*
X1245750Y87717D01*
X1245667Y87217D01*
X1245333Y86800D01*
X1243667Y85967D01*
X1242917Y85383D01*
X1242417Y84550D01*
X1242250Y83800D01*
X1245750D01*
G01X1248517Y85467D02*
X1250683D01*
G01X1253367Y84800D02*
X1253867Y84217D01*
X1254533Y83883D01*
X1255283Y83800D01*
X1255950Y83883D01*
X1256617Y84300D01*
X1257033Y84800D01*
X1257117Y85300D01*
X1256950Y85883D01*
X1256367Y86300D01*
X1255783Y86467D01*
X1255033D01*
G01X1255783D02*
X1256283Y86717D01*
X1256700Y87133D01*
X1256867Y87633D01*
X1256700Y88133D01*
X1256283Y88550D01*
X1255533Y88800D01*
X1254783Y88717D01*
X1254033Y88383D01*
G01X1282000Y53767D02*
Y50433D01*
X1277000D01*
Y53767D01*
G01X1279417Y52433D02*
Y50433D01*
G01X1282000Y55950D02*
X1277000Y59450D01*
G01Y55950D02*
X1282000Y59450D01*
G01Y61633D02*
X1277000D01*
Y63633D01*
X1277250Y64300D01*
X1277833Y64800D01*
X1278500Y64967D01*
X1279167Y64800D01*
X1279667Y64383D01*
X1279917Y63633D01*
Y61633D01*
G01X1282167Y67400D02*
X1277000Y70400D01*
G01X1277417Y76333D02*
X1277167Y75833D01*
X1277000Y75250D01*
Y74583D01*
X1277250Y73833D01*
X1277667Y73250D01*
X1278167Y72833D01*
X1279000Y72500D01*
X1279750Y72417D01*
X1280500Y72583D01*
X1281000Y72833D01*
X1281500Y73333D01*
X1281833Y73917D01*
X1282000Y74500D01*
Y75083D01*
X1281833Y75667D01*
X1281583Y76167D01*
X1281250Y76583D01*
G01X1282000Y78433D02*
X1277000D01*
Y80433D01*
X1277250Y81100D01*
X1277833Y81600D01*
X1278500Y81767D01*
X1279167Y81600D01*
X1279667Y81183D01*
X1279917Y80433D01*
Y78433D01*
G01X1277000Y83867D02*
X1280583D01*
X1281333Y84200D01*
X1281833Y84867D01*
X1282000Y85700D01*
X1281833Y86533D01*
X1281333Y87200D01*
X1280583Y87533D01*
X1277000D01*
G01X1269500Y50333D02*
X1274500D01*
Y53667D01*
G01Y59267D02*
Y55933D01*
X1269500D01*
Y59267D01*
G01X1271917Y57933D02*
Y55933D01*
G01X1274500Y61367D02*
X1269500D01*
Y63033D01*
X1269750Y63700D01*
X1270083Y64200D01*
X1270583Y64617D01*
X1271167Y64950D01*
X1272000Y65033D01*
X1272833Y64950D01*
X1273417Y64617D01*
X1273917Y64200D01*
X1274250Y63700D01*
X1274500Y63033D01*
Y61367D01*
G01Y74400D02*
X1274417Y73733D01*
X1274083Y73150D01*
X1273583Y72650D01*
X1273000Y72317D01*
X1272333Y72150D01*
X1271667D01*
X1271000Y72317D01*
X1270417Y72650D01*
X1269917Y73150D01*
X1269583Y73733D01*
X1269500Y74400D01*
X1269583Y75067D01*
X1269917Y75650D01*
X1270417Y76150D01*
X1271000Y76483D01*
X1271667Y76650D01*
X1272333D01*
X1273000Y76483D01*
X1273583Y76150D01*
X1274083Y75650D01*
X1274417Y75067D01*
X1274500Y74400D01*
G01Y78083D02*
X1269500D01*
X1274500Y81917D01*
X1269500D01*
G01X1274667Y84100D02*
X1269500Y87100D01*
G01X1274500Y91200D02*
X1274417Y90533D01*
X1274083Y89950D01*
X1273583Y89450D01*
X1273000Y89117D01*
X1272333Y88950D01*
X1271667D01*
X1271000Y89117D01*
X1270417Y89450D01*
X1269917Y89950D01*
X1269583Y90533D01*
X1269500Y91200D01*
X1269583Y91867D01*
X1269917Y92450D01*
X1270417Y92950D01*
X1271000Y93283D01*
X1271667Y93450D01*
X1272333D01*
X1273000Y93283D01*
X1273583Y92950D01*
X1274083Y92450D01*
X1274417Y91867D01*
X1274500Y91200D01*
G01Y95217D02*
X1269500D01*
Y98383D01*
G01X1271917Y97217D02*
Y95217D01*
G01X1274500Y100817D02*
X1269500D01*
Y103983D01*
G01X1271917Y102817D02*
Y100817D01*
G01X1274667Y108000D02*
X1274583Y107833D01*
X1274417D01*
X1274333Y108000D01*
X1274417Y108167D01*
X1274583D01*
X1274667Y108000D01*
G01X1272417D02*
X1272333Y107833D01*
X1272167D01*
X1272083Y108000D01*
X1272167Y108167D01*
X1272333D01*
X1272417Y108000D01*
G01X1310750Y27000D02*
Y32000D01*
G01X1314250D02*
Y27000D01*
G01Y29500D02*
X1310750D01*
G01X1320333Y32500D02*
Y27500D01*
X1323667D01*
M02*
